# S9S_MB_2U (Grand Teton) — schematic netlist excerpt (pin names and nets, part order shuffled) for the footprints in the layout excerpt that follows; sources: Cadence DE-HDL packaged netlist, KiCad conversion of 03242023_DA0F0TMBIJ0_F0T_Motherboard_J_brd_V01_OCP.brd

C286  Q_CAP  22UF 4V 20% X6S  pkg C0402  page 77 : A = PVCCIN_CPU1 ; B = GND
R4774  Q_RES  17.8K 1% EMPTY  pkg 0402LF  page 307 : A = P12V_AUX ; B = P12V_AUX_UV_ADR_TRIGGER

(kicad_pcb
	(version 20260206)
	(generator "pcbnew")
	(generator_version "10.0")
	(general
		(thickness 1.6)
		(legacy_teardrops no)
	)
	(paper "A4")
	(title_block
		(title "03242023_DA0F0TMBIJ0_F0T_Motherboard_J_brd_V01_OCP.brd")
		(comment 1 "Grand Teton / footprints 241-242 of 6105")
	)
	(layers
		(0 "F.Cu" signal "TOP")
		(4 "In1.Cu" signal "GND")
		(6 "In2.Cu" signal "IN1")
		(8 "In3.Cu" signal "GND1")
		(10 "In4.Cu" signal "IN2")
		(12 "In5.Cu" signal "GND2")
		(14 "In6.Cu" signal "IN3")
		(16 "In7.Cu" signal "GND3")
		(18 "In8.Cu" signal "VCC")
		(20 "In9.Cu" signal "VCC1")
		(22 "In10.Cu" signal "GND4")
		(24 "In11.Cu" signal "IN4")
		(26 "In12.Cu" signal "GND5")
		(28 "In13.Cu" signal "IN5")
		(30 "In14.Cu" signal "GND6")
		(32 "In15.Cu" signal "IN6")
		(34 "In16.Cu" signal "GND7")
		(2 "B.Cu" signal "BOTTOM")
		(9 "F.Adhes" user "F.Adhesive")
		(11 "B.Adhes" user "B.Adhesive")
		(13 "F.Paste" user "Package Geometry/Pastemask Top")
		(15 "B.Paste" user "Package Geometry/Pastemask Bottom")
		(5 "F.SilkS" user "Ref Des/Silkscreen Top")
		(7 "B.SilkS" user "Ref Des/Silkscreen Bottom")
		(1 "F.Mask" user "Board Geometry/Soldermask Top")
		(3 "B.Mask" user "Board Geometry/Soldermask Bottom")
		(17 "Dwgs.User" user "User.Drawings")
		(19 "Cmts.User" user "User.Comments")
		(21 "Eco1.User" user "User.Eco1")
		(23 "Eco2.User" user "User.Eco2")
		(25 "Edge.Cuts" user "Board Geometry/Outline")
		(27 "Margin" user)
		(31 "F.CrtYd" user "Package Geometry/Place Bound Top")
		(29 "B.CrtYd" user "Package Geometry/Place Bound Bottom")
		(35 "F.Fab" user "Ref Des/Assembly Top")
		(33 "B.Fab" user "Ref Des/Assembly Bottom")
	)
	(footprint ""
		(layer "F.Cu")
		(at 204.724 -92.6338 90)
		(property "Reference" "R4774"
			(at 0 0 90)
			(layer "F.SilkS")
			(hide yes)
			(effects
				(font
					(size 1.27 1.27)
				)
			)
		)
		(property "Value" ""
			(at 0 0 90)
			(layer "F.Fab")
			(effects
				(font
					(size 1.27 1.27)
				)
			)
		)
		(duplicate_pad_numbers_are_jumpers no)
		(fp_line
			(start 0.7874 -0.4064)
			(end 0.7874 0.4064)
			(stroke
				(width 0.1524)
				(type default)
			)
			(layer "F.SilkS")
		)
		(fp_line
			(start -0.7874 -0.4064)
			(end 0.7874 -0.4064)
			(stroke
				(width 0.1524)
				(type default)
			)
			(layer "F.SilkS")
		)
		(fp_line
			(start 0.7874 0.4064)
			(end -0.7874 0.4064)
			(stroke
				(width 0.1524)
				(type default)
			)
			(layer "F.SilkS")
		)
		(fp_line
			(start -0.7874 0.4064)
			(end -0.7874 -0.4064)
			(stroke
				(width 0.1524)
				(type default)
			)
			(layer "F.SilkS")
		)
		(fp_line
			(start -0.12065 -0.305054)
			(end -0.12065 -0.2794)
			(stroke
				(width 0.1)
				(type default)
			)
			(layer "F.Fab")
		)
		(fp_line
			(start -0.67945 -0.305054)
			(end -0.12065 -0.305054)
			(stroke
				(width 0.1)
				(type default)
			)
			(layer "F.Fab")
		)
		(fp_line
			(start 0.67945 -0.3048)
			(end 0.67945 0.3048)
			(stroke
				(width 0.1)
				(type default)
			)
			(layer "F.Fab")
		)
		(fp_line
			(start 0.12065 -0.3048)
			(end 0.67945 -0.3048)
			(stroke
				(width 0.1)
				(type default)
			)
			(layer "F.Fab")
		)
		(fp_line
			(start 0.12065 -0.2794)
			(end 0.12065 -0.3048)
			(stroke
				(width 0.1)
				(type default)
			)
			(layer "F.Fab")
		)
		(fp_line
			(start -0.12065 -0.2794)
			(end 0.12065 -0.2794)
			(stroke
				(width 0.1)
				(type default)
			)
			(layer "F.Fab")
		)
		(fp_line
			(start 0.120396 0.2794)
			(end -0.12065 0.2794)
			(stroke
				(width 0.1)
				(type default)
			)
			(layer "F.Fab")
		)
		(fp_line
			(start -0.12065 0.2794)
			(end -0.12065 0.3048)
			(stroke
				(width 0.1)
				(type default)
			)
			(layer "F.Fab")
		)
		(fp_line
			(start 0.67945 0.3048)
			(end 0.120396 0.3048)
			(stroke
				(width 0.1)
				(type default)
			)
			(layer "F.Fab")
		)
		(fp_line
			(start 0.120396 0.3048)
			(end 0.120396 0.2794)
			(stroke
				(width 0.1)
				(type default)
			)
			(layer "F.Fab")
		)
		(fp_line
			(start -0.12065 0.3048)
			(end -0.67945 0.3048)
			(stroke
				(width 0.1)
				(type default)
			)
			(layer "F.Fab")
		)
		(fp_line
			(start -0.67945 0.3048)
			(end -0.67945 -0.305054)
			(stroke
				(width 0.1)
				(type default)
			)
			(layer "F.Fab")
		)
		(pad "1" smd circle
			(at -0.40005 0 90)
			(size 0 0)
			(layers "F.Cu" "F.Mask" "F.Paste")
			(net "P12V_AUX")
		)
		(pad "2" smd circle
			(at 0.40005 0 90)
			(size 0 0)
			(layers "F.Cu" "F.Mask" "F.Paste")
			(net "P12V_AUX_UV_ADR_TRIGGER")
		)
	)
	(footprint ""
		(layer "F.Cu")
		(at 116.561616 -241.97691 -90)
		(property "Reference" "C286"
			(at 0 0 270)
			(layer "F.SilkS")
			(hide yes)
			(effects
				(font
					(size 1.27 1.27)
				)
			)
		)
		(property "Value" ""
			(at 0 0 270)
			(layer "F.Fab")
			(effects
				(font
					(size 1.27 1.27)
				)
			)
		)
		(duplicate_pad_numbers_are_jumpers no)
		(fp_line
			(start -0.7874 0.4064)
			(end -0.7874 -0.4064)
			(stroke
				(width 0.1524)
				(type default)
			)
			(layer "F.SilkS")
		)
		(fp_line
			(start 0.7874 0.4064)
			(end -0.7874 0.4064)
			(stroke
				(width 0.1524)
				(type default)
			)
			(layer "F.SilkS")
		)
		(fp_line
			(start -0.7874 -0.4064)
			(end 0.7874 -0.4064)
			(stroke
				(width 0.1524)
				(type default)
			)
			(layer "F.SilkS")
		)
		(fp_line
			(start 0.7874 -0.4064)
			(end 0.7874 0.4064)
			(stroke
				(width 0.1524)
				(type default)
			)
			(layer "F.SilkS")
		)
		(fp_line
			(start -0.67945 0.3048)
			(end -0.67945 -0.305054)
			(stroke
				(width 0.1)
				(type default)
			)
			(layer "F.Fab")
		)
		(fp_line
			(start -0.12065 0.3048)
			(end -0.67945 0.3048)
			(stroke
				(width 0.1)
				(type default)
			)
			(layer "F.Fab")
		)
		(fp_line
			(start 0.120396 0.3048)
			(end 0.120396 0.2794)
			(stroke
				(width 0.1)
				(type default)
			)
			(layer "F.Fab")
		)
		(fp_line
			(start 0.67945 0.3048)
			(end 0.120396 0.3048)
			(stroke
				(width 0.1)
				(type default)
			)
			(layer "F.Fab")
		)
		(fp_line
			(start -0.12065 0.2794)
			(end -0.12065 0.3048)
			(stroke
				(width 0.1)
				(type default)
			)
			(layer "F.Fab")
		)
		(fp_line
			(start 0.120396 0.2794)
			(end -0.12065 0.2794)
			(stroke
				(width 0.1)
				(type default)
			)
			(layer "F.Fab")
		)
		(fp_line
			(start -0.12065 -0.2794)
			(end 0.12065 -0.2794)
			(stroke
				(width 0.1)
				(type default)
			)
			(layer "F.Fab")
		)
		(fp_line
			(start 0.12065 -0.2794)
			(end 0.12065 -0.3048)
			(stroke
				(width 0.1)
				(type default)
			)
			(layer "F.Fab")
		)
		(fp_line
			(start 0.12065 -0.3048)
			(end 0.67945 -0.3048)
			(stroke
				(width 0.1)
				(type default)
			)
			(layer "F.Fab")
		)
		(fp_line
			(start 0.67945 -0.3048)
			(end 0.67945 0.3048)
			(stroke
				(width 0.1)
				(type default)
			)
			(layer "F.Fab")
		)
		(fp_line
			(start -0.67945 -0.305054)
			(end -0.12065 -0.305054)
			(stroke
				(width 0.1)
				(type default)
			)
			(layer "F.Fab")
		)
		(fp_line
			(start -0.12065 -0.305054)
			(end -0.12065 -0.2794)
			(stroke
				(width 0.1)
				(type default)
			)
			(layer "F.Fab")
		)
		(pad "1" smd circle
			(at -0.40005 0 270)
			(size 0 0)
			(layers "F.Cu" "F.Mask" "F.Paste")
			(net "PVCCIN_CPU1")
		)
		(pad "2" smd circle
			(at 0.40005 0 270)
			(size 0 0)
			(layers "F.Cu" "F.Mask" "F.Paste")
			(net "GND")
		)
	)
)
